(kicad_pcb
	(version 20260206)
	(generator "pcbnew")
	(generator_version "10.0")
	(general
		(thickness 1.6)
		(legacy_teardrops no)
	)
	(paper "A4")
	(title_block
		(title "04192023_DAF0TMB3IC0_F0TG_MB_C_brd_V02_OCP.brd")
		(comment 1 "Grand Teton / footprint 4188 of 8354 (J28), pads 227-291 of 291")
	)
	(layers
		(0 "F.Cu" signal "TOP")
		(4 "In1.Cu" signal "GND")
		(6 "In2.Cu" signal "IN1")
		(8 "In3.Cu" signal "GND1")
		(10 "In4.Cu" signal "IN2")
		(12 "In5.Cu" signal "GND2")
		(14 "In6.Cu" signal "IN3")
		(16 "In7.Cu" signal "GND3")
		(18 "In8.Cu" signal "VCC")
		(20 "In9.Cu" signal "VCC1")
		(22 "In10.Cu" signal "GND4")
		(24 "In11.Cu" signal "IN4")
		(26 "In12.Cu" signal "GND5")
		(28 "In13.Cu" signal "IN5")
		(30 "In14.Cu" signal "GND6")
		(32 "In15.Cu" signal "IN6")
		(34 "In16.Cu" signal "GND7")
		(2 "B.Cu" signal "BOTTOM")
		(9 "F.Adhes" user "F.Adhesive")
		(11 "B.Adhes" user "B.Adhesive")
		(13 "F.Paste" user "Package Geometry/Pastemask Top")
		(15 "B.Paste" user "Package Geometry/Pastemask Bottom")
		(5 "F.SilkS" user "Ref Des/Silkscreen Top")
		(7 "B.SilkS" user "Ref Des/Silkscreen Bottom")
		(1 "F.Mask" user "Board Geometry/Soldermask Top")
		(3 "B.Mask" user "Board Geometry/Soldermask Bottom")
		(17 "Dwgs.User" user "User.Drawings")
		(19 "Cmts.User" user "User.Comments")
		(21 "Eco1.User" user "User.Eco1")
		(23 "Eco2.User" user "User.Eco2")
		(25 "Edge.Cuts" user "Board Geometry/Outline")
		(27 "Margin" user)
		(31 "F.CrtYd" user "Package Geometry/Place Bound Top")
		(29 "B.CrtYd" user "Package Geometry/Place Bound Bottom")
		(35 "F.Fab" user "Ref Des/Assembly Top")
		(33 "B.Fab" user "Ref Des/Assembly Bottom")
	)
	(footprint ""
		(layer "F.Cu")
		(at 42.289984 -255.560322 180)
		(property "Reference" "J28"
			(at -2.876296 -82.230976 0)
			(unlocked yes)
			(layer "F.SilkS")
			(effects
				(font
					(size 0.7874 0.5842)
					(thickness 0.1524)
				)
			)
		)
		(property "Value" ""
			(at 0 0 180)
			(layer "F.Fab")
			(effects
				(font
					(size 1.27 1.27)
				)
			)
		)
		(duplicate_pad_numbers_are_jumpers no)
		(pad "227" smd rect
			(at 2.050034 11.474958 90)
			(size 0.519938 1.4986)
			(layers "F.Cu" "F.Mask" "F.Paste")
			(net "M_C_CPU1_SB_PAR")
		)
		(pad "228" smd rect
			(at 2.050034 12.325096 90)
			(size 0.519938 1.4986)
			(layers "F.Cu" "F.Mask" "F.Paste")
			(net "GND")
		)
		(pad "229" smd rect
			(at 2.050034 13.17498 90)
			(size 0.519938 1.4986)
			(layers "F.Cu" "F.Mask" "F.Paste")
			(net "M_C_CPU1_SB_CS_N<1>")
		)
		(pad "230" smd rect
			(at 2.050034 14.025118 90)
			(size 0.519938 1.4986)
			(layers "F.Cu" "F.Mask" "F.Paste")
			(net "GND")
		)
		(pad "231" smd rect
			(at 2.050034 14.875002 90)
			(size 0.519938 1.4986)
			(layers "F.Cu" "F.Mask" "F.Paste")
			(net "Net_2289")
		)
		(pad "232" smd rect
			(at 2.050034 15.724886 90)
			(size 0.519938 1.4986)
			(layers "F.Cu" "F.Mask" "F.Paste")
			(net "Net_2290")
		)
		(pad "233" smd rect
			(at 2.050034 16.575024 90)
			(size 0.519938 1.4986)
			(layers "F.Cu" "F.Mask" "F.Paste")
			(net "GND")
		)
		(pad "234" smd rect
			(at 2.050034 17.424908 90)
			(size 0.519938 1.4986)
			(layers "F.Cu" "F.Mask" "F.Paste")
			(net "M_C_CPU1_SB_CB<6>")
		)
		(pad "235" smd rect
			(at 2.050034 18.275046 90)
			(size 0.519938 1.4986)
			(layers "F.Cu" "F.Mask" "F.Paste")
			(net "GND")
		)
		(pad "236" smd rect
			(at 2.050034 19.12493 90)
			(size 0.519938 1.4986)
			(layers "F.Cu" "F.Mask" "F.Paste")
			(net "M_C_CPU1_SB_CB<7>")
		)
		(pad "237" smd rect
			(at 2.050034 19.975068 90)
			(size 0.519938 1.4986)
			(layers "F.Cu" "F.Mask" "F.Paste")
			(net "GND")
		)
		(pad "238" smd rect
			(at 2.050034 20.824952 90)
			(size 0.519938 1.4986)
			(layers "F.Cu" "F.Mask" "F.Paste")
			(net "M_C_CPU1_SB_DQS_DN<4>")
		)
		(pad "239" smd rect
			(at 2.050034 21.67509 90)
			(size 0.519938 1.4986)
			(layers "F.Cu" "F.Mask" "F.Paste")
			(net "M_C_CPU1_SB_DQS_DP<4>")
		)
		(pad "240" smd rect
			(at 2.050034 22.524974 90)
			(size 0.519938 1.4986)
			(layers "F.Cu" "F.Mask" "F.Paste")
			(net "GND")
		)
		(pad "241" smd rect
			(at 2.050034 23.375112 90)
			(size 0.519938 1.4986)
			(layers "F.Cu" "F.Mask" "F.Paste")
			(net "M_C_CPU1_SB_CB<2>")
		)
		(pad "242" smd rect
			(at 2.050034 24.224996 90)
			(size 0.519938 1.4986)
			(layers "F.Cu" "F.Mask" "F.Paste")
			(net "GND")
		)
		(pad "243" smd rect
			(at 2.050034 25.07488 90)
			(size 0.519938 1.4986)
			(layers "F.Cu" "F.Mask" "F.Paste")
			(net "M_C_CPU1_SB_CB<3>")
		)
		(pad "244" smd rect
			(at 2.050034 25.925018 90)
			(size 0.519938 1.4986)
			(layers "F.Cu" "F.Mask" "F.Paste")
			(net "GND")
		)
		(pad "245" smd rect
			(at 2.050034 26.774902 90)
			(size 0.519938 1.4986)
			(layers "F.Cu" "F.Mask" "F.Paste")
			(net "M_C_CPU1_SB_DQ<2>")
		)
		(pad "246" smd rect
			(at 2.050034 27.62504 90)
			(size 0.519938 1.4986)
			(layers "F.Cu" "F.Mask" "F.Paste")
			(net "GND")
		)
		(pad "247" smd rect
			(at 2.050034 28.474924 90)
			(size 0.519938 1.4986)
			(layers "F.Cu" "F.Mask" "F.Paste")
			(net "M_C_CPU1_SB_DQ<3>")
		)
		(pad "248" smd rect
			(at 2.050034 29.325062 90)
			(size 0.519938 1.4986)
			(layers "F.Cu" "F.Mask" "F.Paste")
			(net "GND")
		)
		(pad "249" smd rect
			(at 2.050034 30.174946 90)
			(size 0.519938 1.4986)
			(layers "F.Cu" "F.Mask" "F.Paste")
			(net "M_C_CPU1_SB_DQS_DN<5>")
		)
		(pad "250" smd rect
			(at 2.050034 31.025084 90)
			(size 0.519938 1.4986)
			(layers "F.Cu" "F.Mask" "F.Paste")
			(net "M_C_CPU1_SB_DQS_DP<5>")
		)
		(pad "251" smd rect
			(at 2.050034 31.874968 90)
			(size 0.519938 1.4986)
			(layers "F.Cu" "F.Mask" "F.Paste")
			(net "GND")
		)
		(pad "252" smd rect
			(at 2.050034 32.725106 90)
			(size 0.519938 1.4986)
			(layers "F.Cu" "F.Mask" "F.Paste")
			(net "M_C_CPU1_SB_DQ<6>")
		)
		(pad "253" smd rect
			(at 2.050034 33.57499 90)
			(size 0.519938 1.4986)
			(layers "F.Cu" "F.Mask" "F.Paste")
			(net "GND")
		)
		(pad "254" smd rect
			(at 2.050034 34.425128 90)
			(size 0.519938 1.4986)
			(layers "F.Cu" "F.Mask" "F.Paste")
			(net "M_C_CPU1_SB_DQ<7>")
		)
		(pad "255" smd rect
			(at 2.050034 35.275012 90)
			(size 0.519938 1.4986)
			(layers "F.Cu" "F.Mask" "F.Paste")
			(net "GND")
		)
		(pad "256" smd rect
			(at 2.050034 36.124896 90)
			(size 0.519938 1.4986)
			(layers "F.Cu" "F.Mask" "F.Paste")
			(net "M_C_CPU1_SB_DQ<10>")
		)
		(pad "257" smd rect
			(at 2.050034 36.975034 90)
			(size 0.519938 1.4986)
			(layers "F.Cu" "F.Mask" "F.Paste")
			(net "GND")
		)
		(pad "258" smd rect
			(at 2.050034 37.824918 90)
			(size 0.519938 1.4986)
			(layers "F.Cu" "F.Mask" "F.Paste")
			(net "M_C_CPU1_SB_DQ<11>")
		)
		(pad "259" smd rect
			(at 2.050034 38.675056 90)
			(size 0.519938 1.4986)
			(layers "F.Cu" "F.Mask" "F.Paste")
			(net "GND")
		)
		(pad "260" smd rect
			(at 2.050034 39.52494 90)
			(size 0.519938 1.4986)
			(layers "F.Cu" "F.Mask" "F.Paste")
			(net "M_C_CPU1_SB_DQS_DN<6>")
		)
		(pad "261" smd rect
			(at 2.050034 40.375078 90)
			(size 0.519938 1.4986)
			(layers "F.Cu" "F.Mask" "F.Paste")
			(net "M_C_CPU1_SB_DQS_DP<6>")
		)
		(pad "262" smd rect
			(at 2.050034 41.224962 90)
			(size 0.519938 1.4986)
			(layers "F.Cu" "F.Mask" "F.Paste")
			(net "GND")
		)
		(pad "263" smd rect
			(at 2.050034 42.0751 90)
			(size 0.519938 1.4986)
			(layers "F.Cu" "F.Mask" "F.Paste")
			(net "M_C_CPU1_SB_DQ<14>")
		)
		(pad "264" smd rect
			(at 2.050034 42.924984 90)
			(size 0.519938 1.4986)
			(layers "F.Cu" "F.Mask" "F.Paste")
			(net "GND")
		)
		(pad "265" smd rect
			(at 2.050034 43.775122 90)
			(size 0.519938 1.4986)
			(layers "F.Cu" "F.Mask" "F.Paste")
			(net "M_C_CPU1_SB_DQ<15>")
		)
		(pad "266" smd rect
			(at 2.050034 44.625006 90)
			(size 0.519938 1.4986)
			(layers "F.Cu" "F.Mask" "F.Paste")
			(net "GND")
		)
		(pad "267" smd rect
			(at 2.050034 45.47489 90)
			(size 0.519938 1.4986)
			(layers "F.Cu" "F.Mask" "F.Paste")
			(net "M_C_CPU1_SB_DQ<18>")
		)
		(pad "268" smd rect
			(at 2.050034 46.325028 90)
			(size 0.519938 1.4986)
			(layers "F.Cu" "F.Mask" "F.Paste")
			(net "GND")
		)
		(pad "269" smd rect
			(at 2.050034 47.174912 90)
			(size 0.519938 1.4986)
			(layers "F.Cu" "F.Mask" "F.Paste")
			(net "M_C_CPU1_SB_DQ<19>")
		)
		(pad "270" smd rect
			(at 2.050034 48.02505 90)
			(size 0.519938 1.4986)
			(layers "F.Cu" "F.Mask" "F.Paste")
			(net "GND")
		)
		(pad "271" smd rect
			(at 2.050034 48.874934 90)
			(size 0.519938 1.4986)
			(layers "F.Cu" "F.Mask" "F.Paste")
			(net "M_C_CPU1_SB_DQS_DN<7>")
		)
		(pad "272" smd rect
			(at 2.050034 49.725072 90)
			(size 0.519938 1.4986)
			(layers "F.Cu" "F.Mask" "F.Paste")
			(net "M_C_CPU1_SB_DQS_DP<7>")
		)
		(pad "273" smd rect
			(at 2.050034 50.574956 90)
			(size 0.519938 1.4986)
			(layers "F.Cu" "F.Mask" "F.Paste")
			(net "GND")
		)
		(pad "274" smd rect
			(at 2.050034 51.425094 90)
			(size 0.519938 1.4986)
			(layers "F.Cu" "F.Mask" "F.Paste")
			(net "M_C_CPU1_SB_DQ<22>")
		)
		(pad "275" smd rect
			(at 2.050034 52.274978 90)
			(size 0.519938 1.4986)
			(layers "F.Cu" "F.Mask" "F.Paste")
			(net "GND")
		)
		(pad "276" smd rect
			(at 2.050034 53.125116 90)
			(size 0.519938 1.4986)
			(layers "F.Cu" "F.Mask" "F.Paste")
			(net "M_C_CPU1_SB_DQ<23>")
		)
		(pad "277" smd rect
			(at 2.050034 53.975 90)
			(size 0.519938 1.4986)
			(layers "F.Cu" "F.Mask" "F.Paste")
			(net "GND")
		)
		(pad "278" smd rect
			(at 2.050034 54.824884 90)
			(size 0.519938 1.4986)
			(layers "F.Cu" "F.Mask" "F.Paste")
			(net "M_C_CPU1_SB_DQ<26>")
		)
		(pad "279" smd rect
			(at 2.050034 55.675022 90)
			(size 0.519938 1.4986)
			(layers "F.Cu" "F.Mask" "F.Paste")
			(net "GND")
		)
		(pad "280" smd rect
			(at 2.050034 56.524906 90)
			(size 0.519938 1.4986)
			(layers "F.Cu" "F.Mask" "F.Paste")
			(net "M_C_CPU1_SB_DQ<27>")
		)
		(pad "281" smd rect
			(at 2.050034 57.375044 90)
			(size 0.519938 1.4986)
			(layers "F.Cu" "F.Mask" "F.Paste")
			(net "GND")
		)
		(pad "282" smd rect
			(at 2.050034 58.224928 90)
			(size 0.519938 1.4986)
			(layers "F.Cu" "F.Mask" "F.Paste")
			(net "M_C_CPU1_SB_DQS_DN<8>")
		)
		(pad "283" smd rect
			(at 2.050034 59.075066 90)
			(size 0.519938 1.4986)
			(layers "F.Cu" "F.Mask" "F.Paste")
			(net "M_C_CPU1_SB_DQS_DP<8>")
		)
		(pad "284" smd rect
			(at 2.050034 59.92495 90)
			(size 0.519938 1.4986)
			(layers "F.Cu" "F.Mask" "F.Paste")
			(net "GND")
		)
		(pad "285" smd rect
			(at 2.050034 60.775088 90)
			(size 0.519938 1.4986)
			(layers "F.Cu" "F.Mask" "F.Paste")
			(net "M_C_CPU1_SB_DQ<30>")
		)
		(pad "286" smd rect
			(at 2.050034 61.624972 90)
			(size 0.519938 1.4986)
			(layers "F.Cu" "F.Mask" "F.Paste")
			(net "GND")
		)
		(pad "287" smd rect
			(at 2.050034 62.47511 90)
			(size 0.519938 1.4986)
			(layers "F.Cu" "F.Mask" "F.Paste")
			(net "M_C_CPU1_SB_DQ<31>")
		)
		(pad "288" smd rect
			(at 2.050034 63.324994 90)
			(size 0.519938 1.4986)
			(layers "F.Cu" "F.Mask" "F.Paste")
			(net "GND")
		)
		(pad "G1" thru_hole oval
			(at 0 -68.97497 90)
			(size 1.7272 3.4798)
			(drill oval 1.2192 2.4638)
			(layers "*.Cu" "*.Mask")
			(remove_unused_layers no)
			(net "GND")
			(clearance 0.127)
			(thermal_gap 0.127)
		)
		(pad "G2" thru_hole oval
			(at 0 3.875024 90)
			(size 1.7272 3.4798)
			(drill oval 1.2192 2.4638)
			(layers "*.Cu" "*.Mask")
			(remove_unused_layers no)
			(net "GND")
			(clearance 0.127)
			(thermal_gap 0.127)
		)
		(pad "G3" thru_hole oval
			(at 0 68.97497 90)
			(size 1.7272 3.4798)
			(drill oval 1.2192 2.4638)
			(layers "*.Cu" "*.Mask")
			(remove_unused_layers no)
			(net "GND")
			(clearance 0.127)
			(thermal_gap 0.127)
		)
	)
)
